# S9S_MB_2U (Grand Teton) — schematic netlist excerpt (pin names and nets, part order shuffled) for the footprints in the layout excerpt that follows; sources: Cadence DE-HDL packaged netlist, KiCad conversion of 03242023_DA0F0TMBIJ0_F0T_Motherboard_J_brd_V01_OCP.brd

R3233  Q_RES  0 5% CHIP  pkg 0402LF  page 154 : A = RST_HP_OCP_SFF_R_N ; B = RST_SMB_OCP_SFF_N
PR3968  Q_RES  9.31K 1% EMPTY  pkg 0402LF  page 192 : A = P12V_E1S_CB_0 ; B = GND
H129  HOLE  EMPTY  pkg TH  page 311 : \1\ = GND

(kicad_pcb
	(version 20260206)
	(generator "pcbnew")
	(generator_version "10.0")
	(general
		(thickness 1.6)
		(legacy_teardrops no)
	)
	(paper "A4")
	(title_block
		(title "03242023_DA0F0TMBIJ0_F0T_Motherboard_J_brd_V01_OCP.brd")
		(comment 1 "Grand Teton / footprints 1142-1144 of 6105")
	)
	(layers
		(0 "F.Cu" signal "TOP")
		(4 "In1.Cu" signal "GND")
		(6 "In2.Cu" signal "IN1")
		(8 "In3.Cu" signal "GND1")
		(10 "In4.Cu" signal "IN2")
		(12 "In5.Cu" signal "GND2")
		(14 "In6.Cu" signal "IN3")
		(16 "In7.Cu" signal "GND3")
		(18 "In8.Cu" signal "VCC")
		(20 "In9.Cu" signal "VCC1")
		(22 "In10.Cu" signal "GND4")
		(24 "In11.Cu" signal "IN4")
		(26 "In12.Cu" signal "GND5")
		(28 "In13.Cu" signal "IN5")
		(30 "In14.Cu" signal "GND6")
		(32 "In15.Cu" signal "IN6")
		(34 "In16.Cu" signal "GND7")
		(2 "B.Cu" signal "BOTTOM")
		(9 "F.Adhes" user "F.Adhesive")
		(11 "B.Adhes" user "B.Adhesive")
		(13 "F.Paste" user "Package Geometry/Pastemask Top")
		(15 "B.Paste" user "Package Geometry/Pastemask Bottom")
		(5 "F.SilkS" user "Ref Des/Silkscreen Top")
		(7 "B.SilkS" user "Ref Des/Silkscreen Bottom")
		(1 "F.Mask" user "Board Geometry/Soldermask Top")
		(3 "B.Mask" user "Board Geometry/Soldermask Bottom")
		(17 "Dwgs.User" user "User.Drawings")
		(19 "Cmts.User" user "User.Comments")
		(21 "Eco1.User" user "User.Eco1")
		(23 "Eco2.User" user "User.Eco2")
		(25 "Edge.Cuts" user "Board Geometry/Outline")
		(27 "Margin" user)
		(31 "F.CrtYd" user "Package Geometry/Place Bound Top")
		(29 "B.CrtYd" user "Package Geometry/Place Bound Bottom")
		(35 "F.Fab" user "Ref Des/Assembly Top")
		(33 "B.Fab" user "Ref Des/Assembly Bottom")
	)
	(footprint ""
		(layer "F.Cu")
		(at 253.08941 -44.849542 90)
		(property "Reference" "PR3968"
			(at 0 0 90)
			(layer "F.SilkS")
			(hide yes)
			(effects
				(font
					(size 1.27 1.27)
				)
			)
		)
		(property "Value" ""
			(at 0 0 90)
			(layer "F.Fab")
			(effects
				(font
					(size 1.27 1.27)
				)
			)
		)
		(duplicate_pad_numbers_are_jumpers no)
		(fp_line
			(start 0.7874 -0.4064)
			(end 0.7874 0.4064)
			(stroke
				(width 0.1524)
				(type default)
			)
			(layer "F.SilkS")
		)
		(fp_line
			(start -0.7874 -0.4064)
			(end 0.7874 -0.4064)
			(stroke
				(width 0.1524)
				(type default)
			)
			(layer "F.SilkS")
		)
		(fp_line
			(start 0.7874 0.4064)
			(end -0.7874 0.4064)
			(stroke
				(width 0.1524)
				(type default)
			)
			(layer "F.SilkS")
		)
		(fp_line
			(start -0.7874 0.4064)
			(end -0.7874 -0.4064)
			(stroke
				(width 0.1524)
				(type default)
			)
			(layer "F.SilkS")
		)
		(fp_line
			(start -0.12065 -0.305054)
			(end -0.12065 -0.2794)
			(stroke
				(width 0.1)
				(type default)
			)
			(layer "F.Fab")
		)
		(fp_line
			(start -0.67945 -0.305054)
			(end -0.12065 -0.305054)
			(stroke
				(width 0.1)
				(type default)
			)
			(layer "F.Fab")
		)
		(fp_line
			(start 0.67945 -0.3048)
			(end 0.67945 0.3048)
			(stroke
				(width 0.1)
				(type default)
			)
			(layer "F.Fab")
		)
		(fp_line
			(start 0.12065 -0.3048)
			(end 0.67945 -0.3048)
			(stroke
				(width 0.1)
				(type default)
			)
			(layer "F.Fab")
		)
		(fp_line
			(start 0.12065 -0.2794)
			(end 0.12065 -0.3048)
			(stroke
				(width 0.1)
				(type default)
			)
			(layer "F.Fab")
		)
		(fp_line
			(start -0.12065 -0.2794)
			(end 0.12065 -0.2794)
			(stroke
				(width 0.1)
				(type default)
			)
			(layer "F.Fab")
		)
		(fp_line
			(start 0.120396 0.2794)
			(end -0.12065 0.2794)
			(stroke
				(width 0.1)
				(type default)
			)
			(layer "F.Fab")
		)
		(fp_line
			(start -0.12065 0.2794)
			(end -0.12065 0.3048)
			(stroke
				(width 0.1)
				(type default)
			)
			(layer "F.Fab")
		)
		(fp_line
			(start 0.67945 0.3048)
			(end 0.120396 0.3048)
			(stroke
				(width 0.1)
				(type default)
			)
			(layer "F.Fab")
		)
		(fp_line
			(start 0.120396 0.3048)
			(end 0.120396 0.2794)
			(stroke
				(width 0.1)
				(type default)
			)
			(layer "F.Fab")
		)
		(fp_line
			(start -0.12065 0.3048)
			(end -0.67945 0.3048)
			(stroke
				(width 0.1)
				(type default)
			)
			(layer "F.Fab")
		)
		(fp_line
			(start -0.67945 0.3048)
			(end -0.67945 -0.305054)
			(stroke
				(width 0.1)
				(type default)
			)
			(layer "F.Fab")
		)
		(pad "1" smd circle
			(at -0.40005 0 90)
			(size 0 0)
			(layers "F.Cu" "F.Mask" "F.Paste")
			(net "P12V_E1S_CB_0")
		)
		(pad "2" smd circle
			(at 0.40005 0 90)
			(size 0 0)
			(layers "F.Cu" "F.Mask" "F.Paste")
			(net "GND")
		)
	)
	(footprint ""
		(layer "F.Cu")
		(at 287.979866 -419.999922)
		(property "Reference" "H129"
			(at -3.46456 -4.95681 0)
			(unlocked yes)
			(layer "F.SilkS")
			(effects
				(font
					(size 0.7874 0.5842)
					(thickness 0.1524)
				)
				(justify left)
			)
		)
		(property "Value" ""
			(at 0 0 0)
			(layer "F.Fab")
			(effects
				(font
					(size 1.27 1.27)
				)
			)
		)
		(duplicate_pad_numbers_are_jumpers no)
		(pad "1" thru_hole circle
			(at 0 0)
			(size 8.001 8.001)
			(drill 4.2164)
			(layers "*.Cu" "*.Mask")
			(remove_unused_layers no)
			(net "GND")
			(clearance -1.6383)
		)
	)
	(footprint ""
		(layer "F.Cu")
		(at 463.562954 -92.387674)
		(property "Reference" "R3233"
			(at 0 0 0)
			(layer "F.SilkS")
			(hide yes)
			(effects
				(font
					(size 1.27 1.27)
				)
			)
		)
		(property "Value" ""
			(at 0 0 0)
			(layer "F.Fab")
			(effects
				(font
					(size 1.27 1.27)
				)
			)
		)
		(duplicate_pad_numbers_are_jumpers no)
		(fp_line
			(start -0.7874 -0.4064)
			(end 0.7874 -0.4064)
			(stroke
				(width 0.1524)
				(type default)
			)
			(layer "F.SilkS")
		)
		(fp_line
			(start -0.7874 0.4064)
			(end -0.7874 -0.4064)
			(stroke
				(width 0.1524)
				(type default)
			)
			(layer "F.SilkS")
		)
		(fp_line
			(start 0.7874 -0.4064)
			(end 0.7874 0.4064)
			(stroke
				(width 0.1524)
				(type default)
			)
			(layer "F.SilkS")
		)
		(fp_line
			(start 0.7874 0.4064)
			(end -0.7874 0.4064)
			(stroke
				(width 0.1524)
				(type default)
			)
			(layer "F.SilkS")
		)
		(fp_line
			(start -0.67945 -0.305054)
			(end -0.12065 -0.305054)
			(stroke
				(width 0.1)
				(type default)
			)
			(layer "F.Fab")
		)
		(fp_line
			(start -0.67945 0.3048)
			(end -0.67945 -0.305054)
			(stroke
				(width 0.1)
				(type default)
			)
			(layer "F.Fab")
		)
		(fp_line
			(start -0.12065 -0.305054)
			(end -0.12065 -0.2794)
			(stroke
				(width 0.1)
				(type default)
			)
			(layer "F.Fab")
		)
		(fp_line
			(start -0.12065 -0.2794)
			(end 0.12065 -0.2794)
			(stroke
				(width 0.1)
				(type default)
			)
			(layer "F.Fab")
		)
		(fp_line
			(start -0.12065 0.2794)
			(end -0.12065 0.3048)
			(stroke
				(width 0.1)
				(type default)
			)
			(layer "F.Fab")
		)
		(fp_line
			(start -0.12065 0.3048)
			(end -0.67945 0.3048)
			(stroke
				(width 0.1)
				(type default)
			)
			(layer "F.Fab")
		)
		(fp_line
			(start 0.120396 0.2794)
			(end -0.12065 0.2794)
			(stroke
				(width 0.1)
				(type default)
			)
			(layer "F.Fab")
		)
		(fp_line
			(start 0.120396 0.3048)
			(end 0.120396 0.2794)
			(stroke
				(width 0.1)
				(type default)
			)
			(layer "F.Fab")
		)
		(fp_line
			(start 0.12065 -0.3048)
			(end 0.67945 -0.3048)
			(stroke
				(width 0.1)
				(type default)
			)
			(layer "F.Fab")
		)
		(fp_line
			(start 0.12065 -0.2794)
			(end 0.12065 -0.3048)
			(stroke
				(width 0.1)
				(type default)
			)
			(layer "F.Fab")
		)
		(fp_line
			(start 0.67945 -0.3048)
			(end 0.67945 0.3048)
			(stroke
				(width 0.1)
				(type default)
			)
			(layer "F.Fab")
		)
		(fp_line
			(start 0.67945 0.3048)
			(end 0.120396 0.3048)
			(stroke
				(width 0.1)
				(type default)
			)
			(layer "F.Fab")
		)
		(pad "1" smd circle
			(at -0.40005 0)
			(size 0 0)
			(layers "F.Cu" "F.Mask" "F.Paste")
			(net "RST_HP_OCP_SFF_R_N")
		)
		(pad "2" smd circle
			(at 0.40005 0)
			(size 0 0)
			(layers "F.Cu" "F.Mask" "F.Paste")
			(net "RST_SMB_OCP_SFF_N")
		)
	)
)
